# T6G (Grand Teton) — schematic netlist excerpt (pin names and nets, part order shuffled) for the footprints in the layout excerpt that follows; sources: Cadence DE-HDL packaged netlist, KiCad conversion of 04192023_DAF0TMB3IC0_F0TG_MB_C_brd_V02_OCP.brd

C1830  Q_CAP  22UF 16V 20% X6S  pkg C0805  page 137 : A = P12V_OCP_V3_2_R ; B = GND
R1231  Q_RES  5.11K 1% CHIP  pkg 0402LF  page 258 : A = P1V8_CPU0_RT_1D ; B = P1V8_CPU0_RT_1D_ADC
PC590_2  Q_CAP  22UF 16V 20% X6S  pkg C0805  page 198 : A = SW_P12V_AUX_PVDDCR_SOC_P0_FLT ; B = GND
C6749  Q_CAP_DIFFBUS  DIFF BUS_0.22UF 6.3V 20% X6S  pkg C0201  page 352 : \1\ = P5E_CPU1_P3_TX_BUF_C_DP<12> ; \2\ = P5E_CPU1_P3_TX_BUF_DP<12>

(kicad_pcb
	(version 20260206)
	(generator "pcbnew")
	(generator_version "10.0")
	(general
		(thickness 1.6)
		(legacy_teardrops no)
	)
	(paper "A4")
	(title_block
		(title "04192023_DAF0TMB3IC0_F0TG_MB_C_brd_V02_OCP.brd")
		(comment 1 "Grand Teton / footprints 6126-6129 of 8354")
	)
	(layers
		(0 "F.Cu" signal "TOP")
		(4 "In1.Cu" signal "GND")
		(6 "In2.Cu" signal "IN1")
		(8 "In3.Cu" signal "GND1")
		(10 "In4.Cu" signal "IN2")
		(12 "In5.Cu" signal "GND2")
		(14 "In6.Cu" signal "IN3")
		(16 "In7.Cu" signal "GND3")
		(18 "In8.Cu" signal "VCC")
		(20 "In9.Cu" signal "VCC1")
		(22 "In10.Cu" signal "GND4")
		(24 "In11.Cu" signal "IN4")
		(26 "In12.Cu" signal "GND5")
		(28 "In13.Cu" signal "IN5")
		(30 "In14.Cu" signal "GND6")
		(32 "In15.Cu" signal "IN6")
		(34 "In16.Cu" signal "GND7")
		(2 "B.Cu" signal "BOTTOM")
		(9 "F.Adhes" user "F.Adhesive")
		(11 "B.Adhes" user "B.Adhesive")
		(13 "F.Paste" user "Package Geometry/Pastemask Top")
		(15 "B.Paste" user "Package Geometry/Pastemask Bottom")
		(5 "F.SilkS" user "Ref Des/Silkscreen Top")
		(7 "B.SilkS" user "Ref Des/Silkscreen Bottom")
		(1 "F.Mask" user "Board Geometry/Soldermask Top")
		(3 "B.Mask" user "Board Geometry/Soldermask Bottom")
		(17 "Dwgs.User" user "User.Drawings")
		(19 "Cmts.User" user "User.Comments")
		(21 "Eco1.User" user "User.Eco1")
		(23 "Eco2.User" user "User.Eco2")
		(25 "Edge.Cuts" user "Board Geometry/Outline")
		(27 "Margin" user)
		(31 "F.CrtYd" user "Package Geometry/Place Bound Top")
		(29 "B.CrtYd" user "Package Geometry/Place Bound Bottom")
		(35 "F.Fab" user "Ref Des/Assembly Top")
		(33 "B.Fab" user "Ref Des/Assembly Bottom")
	)
	(footprint ""
		(layer "B.Cu")
		(at 405.120856 -168.717468 -90)
		(property "Reference" "PC590_2"
			(at 0 0 90)
			(layer "B.SilkS")
			(hide yes)
			(effects
				(font
					(size 1.27 1.27)
				)
				(justify mirror)
			)
		)
		(property "Value" ""
			(at 0 0 90)
			(layer "B.Fab")
			(effects
				(font
					(size 1.27 1.27)
				)
				(justify mirror)
			)
		)
		(duplicate_pad_numbers_are_jumpers no)
		(fp_line
			(start -1.524 0.762)
			(end 1.524 0.762)
			(stroke
				(width 0.1524)
				(type default)
			)
			(layer "B.SilkS")
		)
		(fp_line
			(start 1.524 0.762)
			(end 1.524 -0.762)
			(stroke
				(width 0.1524)
				(type default)
			)
			(layer "B.SilkS")
		)
		(fp_line
			(start -1.524 -0.762)
			(end -1.524 0.762)
			(stroke
				(width 0.1524)
				(type default)
			)
			(layer "B.SilkS")
		)
		(fp_line
			(start 1.524 -0.762)
			(end -1.524 -0.762)
			(stroke
				(width 0.1524)
				(type default)
			)
			(layer "B.SilkS")
		)
		(fp_line
			(start -1.1049 0.724916)
			(end -1.1049 -0.724916)
			(stroke
				(width 0.1)
				(type default)
			)
			(layer "B.Fab")
		)
		(fp_line
			(start 1.1049 0.724916)
			(end -1.1049 0.724916)
			(stroke
				(width 0.1)
				(type default)
			)
			(layer "B.Fab")
		)
		(fp_line
			(start -1.1049 -0.724916)
			(end 1.1049 -0.724916)
			(stroke
				(width 0.1)
				(type default)
			)
			(layer "B.Fab")
		)
		(fp_line
			(start 1.1049 -0.724916)
			(end 1.1049 0.724916)
			(stroke
				(width 0.1)
				(type default)
			)
			(layer "B.Fab")
		)
		(pad "1" smd rect
			(at 0.889 0 270)
			(size 1.016 1.27)
			(layers "B.Cu" "B.Mask" "B.Paste")
			(net "SW_P12V_AUX_PVDDCR_SOC_P0_FLT")
		)
		(pad "2" smd rect
			(at -0.889 0 270)
			(size 1.016 1.27)
			(layers "B.Cu" "B.Mask" "B.Paste")
			(net "GND")
		)
	)
	(footprint ""
		(layer "B.Cu")
		(at 154.073606 -408.517344 90)
		(property "Reference" "C6749"
			(at 0 0 90)
			(layer "B.SilkS")
			(hide yes)
			(effects
				(font
					(size 1.27 1.27)
				)
				(justify mirror)
			)
		)
		(property "Value" ""
			(at 0 0 90)
			(layer "B.Fab")
			(effects
				(font
					(size 1.27 1.27)
				)
				(justify mirror)
			)
		)
		(duplicate_pad_numbers_are_jumpers no)
		(fp_line
			(start 0.299974 -0.150114)
			(end -0.299974 -0.150114)
			(stroke
				(width 0.1)
				(type default)
			)
			(layer "B.Fab")
		)
		(fp_line
			(start -0.299974 -0.150114)
			(end -0.299974 0.150114)
			(stroke
				(width 0.1)
				(type default)
			)
			(layer "B.Fab")
		)
		(fp_line
			(start 0.299974 0.150114)
			(end 0.299974 -0.150114)
			(stroke
				(width 0.1)
				(type default)
			)
			(layer "B.Fab")
		)
		(fp_line
			(start -0.299974 0.150114)
			(end 0.299974 0.150114)
			(stroke
				(width 0.1)
				(type default)
			)
			(layer "B.Fab")
		)
		(pad "1" smd rect
			(at 0.2667 0 270)
			(size 0.3048 0.381)
			(layers "B.Cu" "B.Mask" "B.Paste")
			(net "P5E_CPU1_P3_TX_BUF_C_DP<12>")
		)
		(pad "2" smd rect
			(at -0.2667 0 270)
			(size 0.3048 0.381)
			(layers "B.Cu" "B.Mask" "B.Paste")
			(net "P5E_CPU1_P3_TX_BUF_DP<12>")
		)
	)
	(footprint ""
		(layer "B.Cu")
		(at 65.193164 -17.227804)
		(property "Reference" "C1830"
			(at 0 0 0)
			(layer "B.SilkS")
			(hide yes)
			(effects
				(font
					(size 1.27 1.27)
				)
				(justify mirror)
			)
		)
		(property "Value" ""
			(at 0 0 0)
			(layer "B.Fab")
			(effects
				(font
					(size 1.27 1.27)
				)
				(justify mirror)
			)
		)
		(duplicate_pad_numbers_are_jumpers no)
		(fp_line
			(start -1.524 -0.762)
			(end -1.524 0.762)
			(stroke
				(width 0.1524)
				(type default)
			)
			(layer "B.SilkS")
		)
		(fp_line
			(start -1.524 0.762)
			(end 1.524 0.762)
			(stroke
				(width 0.1524)
				(type default)
			)
			(layer "B.SilkS")
		)
		(fp_line
			(start 1.524 -0.762)
			(end -1.524 -0.762)
			(stroke
				(width 0.1524)
				(type default)
			)
			(layer "B.SilkS")
		)
		(fp_line
			(start 1.524 0.762)
			(end 1.524 -0.762)
			(stroke
				(width 0.1524)
				(type default)
			)
			(layer "B.SilkS")
		)
		(fp_line
			(start -1.1049 -0.724916)
			(end 1.1049 -0.724916)
			(stroke
				(width 0.1)
				(type default)
			)
			(layer "B.Fab")
		)
		(fp_line
			(start -1.1049 0.724916)
			(end -1.1049 -0.724916)
			(stroke
				(width 0.1)
				(type default)
			)
			(layer "B.Fab")
		)
		(fp_line
			(start 1.1049 -0.724916)
			(end 1.1049 0.724916)
			(stroke
				(width 0.1)
				(type default)
			)
			(layer "B.Fab")
		)
		(fp_line
			(start 1.1049 0.724916)
			(end -1.1049 0.724916)
			(stroke
				(width 0.1)
				(type default)
			)
			(layer "B.Fab")
		)
		(pad "1" smd rect
			(at 0.889 0)
			(size 1.016 1.27)
			(layers "B.Cu" "B.Mask" "B.Paste")
			(net "P12V_OCP_V3_2_R")
		)
		(pad "2" smd rect
			(at -0.889 0)
			(size 1.016 1.27)
			(layers "B.Cu" "B.Mask" "B.Paste")
			(net "GND")
		)
	)
	(footprint ""
		(layer "B.Cu")
		(at 237.917482 -324.626986)
		(property "Reference" "R1231"
			(at 0 0 0)
			(layer "B.SilkS")
			(hide yes)
			(effects
				(font
					(size 1.27 1.27)
				)
				(justify mirror)
			)
		)
		(property "Value" ""
			(at 0 0 0)
			(layer "B.Fab")
			(effects
				(font
					(size 1.27 1.27)
				)
				(justify mirror)
			)
		)
		(duplicate_pad_numbers_are_jumpers no)
		(fp_line
			(start -0.7874 -0.4064)
			(end -0.7874 0.4064)
			(stroke
				(width 0.1524)
				(type default)
			)
			(layer "B.SilkS")
		)
		(fp_line
			(start -0.7874 0.4064)
			(end 0.7874 0.4064)
			(stroke
				(width 0.1524)
				(type default)
			)
			(layer "B.SilkS")
		)
		(fp_line
			(start 0.7874 -0.4064)
			(end -0.7874 -0.4064)
			(stroke
				(width 0.1524)
				(type default)
			)
			(layer "B.SilkS")
		)
		(fp_line
			(start 0.7874 0.4064)
			(end 0.7874 -0.4064)
			(stroke
				(width 0.1524)
				(type default)
			)
			(layer "B.SilkS")
		)
		(fp_line
			(start -0.67945 -0.3048)
			(end -0.67945 0.3048)
			(stroke
				(width 0.1)
				(type default)
			)
			(layer "B.Fab")
		)
		(fp_line
			(start -0.67945 0.3048)
			(end -0.120396 0.3048)
			(stroke
				(width 0.1)
				(type default)
			)
			(layer "B.Fab")
		)
		(fp_line
			(start -0.12065 -0.3048)
			(end -0.67945 -0.3048)
			(stroke
				(width 0.1)
				(type default)
			)
			(layer "B.Fab")
		)
		(fp_line
			(start -0.12065 -0.2794)
			(end -0.12065 -0.3048)
			(stroke
				(width 0.1)
				(type default)
			)
			(layer "B.Fab")
		)
		(fp_line
			(start -0.120396 0.2794)
			(end 0.12065 0.2794)
			(stroke
				(width 0.1)
				(type default)
			)
			(layer "B.Fab")
		)
		(fp_line
			(start -0.120396 0.3048)
			(end -0.120396 0.2794)
			(stroke
				(width 0.1)
				(type default)
			)
			(layer "B.Fab")
		)
		(fp_line
			(start 0.12065 -0.305054)
			(end 0.12065 -0.2794)
			(stroke
				(width 0.1)
				(type default)
			)
			(layer "B.Fab")
		)
		(fp_line
			(start 0.12065 -0.2794)
			(end -0.12065 -0.2794)
			(stroke
				(width 0.1)
				(type default)
			)
			(layer "B.Fab")
		)
		(fp_line
			(start 0.12065 0.2794)
			(end 0.12065 0.3048)
			(stroke
				(width 0.1)
				(type default)
			)
			(layer "B.Fab")
		)
		(fp_line
			(start 0.12065 0.3048)
			(end 0.67945 0.3048)
			(stroke
				(width 0.1)
				(type default)
			)
			(layer "B.Fab")
		)
		(fp_line
			(start 0.67945 -0.305054)
			(end 0.12065 -0.305054)
			(stroke
				(width 0.1)
				(type default)
			)
			(layer "B.Fab")
		)
		(fp_line
			(start 0.67945 0.3048)
			(end 0.67945 -0.305054)
			(stroke
				(width 0.1)
				(type default)
			)
			(layer "B.Fab")
		)
		(pad "1" smd circle
			(at 0.40005 0 180)
			(size 0 0)
			(layers "B.Cu" "B.Mask" "B.Paste")
			(net "P1V8_CPU0_RT_1D")
		)
		(pad "2" smd circle
			(at -0.40005 0 180)
			(size 0 0)
			(layers "B.Cu" "B.Mask" "B.Paste")
			(net "P1V8_CPU0_RT_1D_ADC")
		)
	)
)
